# S9S_MB_2U (Grand Teton) — schematic netlist excerpt (pin names and nets, part order shuffled) for the footprints in the layout excerpt that follows; sources: Cadence DE-HDL packaged netlist, KiCad conversion of 03242023_DA0F0TMBIJ0_F0T_Motherboard_J_brd_V01_OCP.brd

C2354  Q_CAP  0.1UF 25V 10% EMPTY  pkg 0402  page 167 : A = P2E_MB_BMC_RX_BUF2_C_DN<0> ; B = P2E_MB_BMC_RX_BUF_DN<0>
PC1593  Q_CAPP  560UF 2.5V 20% OSCON  pkg THLF  page 293 : A = PVCCINFAON_CPU1 ; B = GND
R587  Q_RES  1K 1% CHIP  pkg 0402LF  page 231 : A = PCA9548_PCIE3_ADDR0 ; B = GND

(kicad_pcb
	(version 20260206)
	(generator "pcbnew")
	(generator_version "10.0")
	(general
		(thickness 1.6)
		(legacy_teardrops no)
	)
	(paper "A4")
	(title_block
		(title "03242023_DA0F0TMBIJ0_F0T_Motherboard_J_brd_V01_OCP.brd")
		(comment 1 "Grand Teton / footprints 1052-1054 of 6105")
	)
	(layers
		(0 "F.Cu" signal "TOP")
		(4 "In1.Cu" signal "GND")
		(6 "In2.Cu" signal "IN1")
		(8 "In3.Cu" signal "GND1")
		(10 "In4.Cu" signal "IN2")
		(12 "In5.Cu" signal "GND2")
		(14 "In6.Cu" signal "IN3")
		(16 "In7.Cu" signal "GND3")
		(18 "In8.Cu" signal "VCC")
		(20 "In9.Cu" signal "VCC1")
		(22 "In10.Cu" signal "GND4")
		(24 "In11.Cu" signal "IN4")
		(26 "In12.Cu" signal "GND5")
		(28 "In13.Cu" signal "IN5")
		(30 "In14.Cu" signal "GND6")
		(32 "In15.Cu" signal "IN6")
		(34 "In16.Cu" signal "GND7")
		(2 "B.Cu" signal "BOTTOM")
		(9 "F.Adhes" user "F.Adhesive")
		(11 "B.Adhes" user "B.Adhesive")
		(13 "F.Paste" user "Package Geometry/Pastemask Top")
		(15 "B.Paste" user "Package Geometry/Pastemask Bottom")
		(5 "F.SilkS" user "Ref Des/Silkscreen Top")
		(7 "B.SilkS" user "Ref Des/Silkscreen Bottom")
		(1 "F.Mask" user "Board Geometry/Soldermask Top")
		(3 "B.Mask" user "Board Geometry/Soldermask Bottom")
		(17 "Dwgs.User" user "User.Drawings")
		(19 "Cmts.User" user "User.Comments")
		(21 "Eco1.User" user "User.Eco1")
		(23 "Eco2.User" user "User.Eco2")
		(25 "Edge.Cuts" user "Board Geometry/Outline")
		(27 "Margin" user)
		(31 "F.CrtYd" user "Package Geometry/Place Bound Top")
		(29 "B.CrtYd" user "Package Geometry/Place Bound Bottom")
		(35 "F.Fab" user "Ref Des/Assembly Top")
		(33 "B.Fab" user "Ref Des/Assembly Bottom")
	)
	(footprint ""
		(layer "F.Cu")
		(at 113.494312 -139.069826 180)
		(property "Reference" "R587"
			(at 0 0 180)
			(layer "F.SilkS")
			(hide yes)
			(effects
				(font
					(size 1.27 1.27)
				)
			)
		)
		(property "Value" ""
			(at 0 0 180)
			(layer "F.Fab")
			(effects
				(font
					(size 1.27 1.27)
				)
			)
		)
		(duplicate_pad_numbers_are_jumpers no)
		(fp_line
			(start 0.7874 0.4064)
			(end -0.7874 0.4064)
			(stroke
				(width 0.1524)
				(type default)
			)
			(layer "F.SilkS")
		)
		(fp_line
			(start 0.7874 -0.4064)
			(end 0.7874 0.4064)
			(stroke
				(width 0.1524)
				(type default)
			)
			(layer "F.SilkS")
		)
		(fp_line
			(start -0.7874 0.4064)
			(end -0.7874 -0.4064)
			(stroke
				(width 0.1524)
				(type default)
			)
			(layer "F.SilkS")
		)
		(fp_line
			(start -0.7874 -0.4064)
			(end 0.7874 -0.4064)
			(stroke
				(width 0.1524)
				(type default)
			)
			(layer "F.SilkS")
		)
		(fp_line
			(start 0.67945 0.3048)
			(end 0.120396 0.3048)
			(stroke
				(width 0.1)
				(type default)
			)
			(layer "F.Fab")
		)
		(fp_line
			(start 0.67945 -0.3048)
			(end 0.67945 0.3048)
			(stroke
				(width 0.1)
				(type default)
			)
			(layer "F.Fab")
		)
		(fp_line
			(start 0.12065 -0.2794)
			(end 0.12065 -0.3048)
			(stroke
				(width 0.1)
				(type default)
			)
			(layer "F.Fab")
		)
		(fp_line
			(start 0.12065 -0.3048)
			(end 0.67945 -0.3048)
			(stroke
				(width 0.1)
				(type default)
			)
			(layer "F.Fab")
		)
		(fp_line
			(start 0.120396 0.3048)
			(end 0.120396 0.2794)
			(stroke
				(width 0.1)
				(type default)
			)
			(layer "F.Fab")
		)
		(fp_line
			(start 0.120396 0.2794)
			(end -0.12065 0.2794)
			(stroke
				(width 0.1)
				(type default)
			)
			(layer "F.Fab")
		)
		(fp_line
			(start -0.12065 0.3048)
			(end -0.67945 0.3048)
			(stroke
				(width 0.1)
				(type default)
			)
			(layer "F.Fab")
		)
		(fp_line
			(start -0.12065 0.2794)
			(end -0.12065 0.3048)
			(stroke
				(width 0.1)
				(type default)
			)
			(layer "F.Fab")
		)
		(fp_line
			(start -0.12065 -0.2794)
			(end 0.12065 -0.2794)
			(stroke
				(width 0.1)
				(type default)
			)
			(layer "F.Fab")
		)
		(fp_line
			(start -0.12065 -0.305054)
			(end -0.12065 -0.2794)
			(stroke
				(width 0.1)
				(type default)
			)
			(layer "F.Fab")
		)
		(fp_line
			(start -0.67945 0.3048)
			(end -0.67945 -0.305054)
			(stroke
				(width 0.1)
				(type default)
			)
			(layer "F.Fab")
		)
		(fp_line
			(start -0.67945 -0.305054)
			(end -0.12065 -0.305054)
			(stroke
				(width 0.1)
				(type default)
			)
			(layer "F.Fab")
		)
		(pad "1" smd circle
			(at -0.40005 0 180)
			(size 0 0)
			(layers "F.Cu" "F.Mask" "F.Paste")
			(net "PCA9548_PCIE3_ADDR0")
		)
		(pad "2" smd circle
			(at 0.40005 0 180)
			(size 0 0)
			(layers "F.Cu" "F.Mask" "F.Paste")
			(net "GND")
		)
	)
	(footprint ""
		(layer "F.Cu")
		(at 69.923406 -148.228304)
		(property "Reference" "PC1593"
			(at 0 0 0)
			(layer "F.SilkS")
			(hide yes)
			(effects
				(font
					(size 1.27 1.27)
				)
			)
		)
		(property "Value" ""
			(at 0 0 0)
			(layer "F.Fab")
			(effects
				(font
					(size 1.27 1.27)
				)
			)
		)
		(duplicate_pad_numbers_are_jumpers no)
		(fp_line
			(start 2.750058 0.999998)
			(end -2.750058 0.999998)
			(stroke
				(width 0.1524)
				(type default)
			)
			(layer "F.SilkS")
		)
		(fp_circle
			(center 0 0.999998)
			(end 2.750058 0.999998)
			(stroke
				(width 0.1524)
				(type default)
			)
			(fill no)
			(layer "F.SilkS")
		)
		(fp_poly
			(pts
				(arc
					(start 2.750058 0.999998)
					(mid 0 3.750056)
					(end -2.750058 0.999998)
				)
			)
			(stroke
				(width 0)
				(type default)
			)
			(fill yes)
			(layer "F.SilkS")
		)
		(fp_circle
			(center 0 0.999998)
			(end 2.750058 0.999998)
			(stroke
				(width 0.1)
				(type default)
			)
			(fill no)
			(layer "F.Fab")
		)
		(pad "1" thru_hole rect
			(at 0 0)
			(size 1.5748 1.5748)
			(drill 1.0668)
			(layers "*.Cu" "*.Mask")
			(remove_unused_layers no)
			(net "PVCCINFAON_CPU1")
			(clearance 0)
			(padstack
				(mode front_inner_back)
				(layer "Inner"
					(shape circle)
					(size 1.5748 1.5748)
					(clearance 0)
				)
				(layer "B.Cu"
					(shape rect)
					(size 1.5748 1.5748)
					(clearance 0)
				)
			)
		)
		(pad "2" thru_hole circle
			(at 0 1.999996)
			(size 1.5748 1.5748)
			(drill 1.0668)
			(layers "*.Cu" "*.Mask")
			(remove_unused_layers no)
			(net "GND")
			(clearance 0)
		)
	)
	(footprint ""
		(layer "F.Cu")
		(at 22.460204 -384.978148 90)
		(property "Reference" "C2354"
			(at 0 0 90)
			(layer "F.SilkS")
			(hide yes)
			(effects
				(font
					(size 1.27 1.27)
				)
			)
		)
		(property "Value" ""
			(at 0 0 90)
			(layer "F.Fab")
			(effects
				(font
					(size 1.27 1.27)
				)
			)
		)
		(duplicate_pad_numbers_are_jumpers no)
		(fp_line
			(start 0.7874 -0.4064)
			(end 0.7874 0.4064)
			(stroke
				(width 0.1524)
				(type default)
			)
			(layer "F.SilkS")
		)
		(fp_line
			(start -0.7874 -0.4064)
			(end 0.7874 -0.4064)
			(stroke
				(width 0.1524)
				(type default)
			)
			(layer "F.SilkS")
		)
		(fp_line
			(start -0.005588 0.4064)
			(end -0.7874 0.4064)
			(stroke
				(width 0.1524)
				(type default)
			)
			(layer "F.SilkS")
		)
		(fp_line
			(start 0.6858 -0.3048)
			(end 0.6858 0.3048)
			(stroke
				(width 0.1)
				(type default)
			)
			(layer "F.Fab")
		)
		(fp_line
			(start 0.1016 -0.3048)
			(end 0.6858 -0.3048)
			(stroke
				(width 0.1)
				(type default)
			)
			(layer "F.Fab")
		)
		(fp_line
			(start -0.1016 -0.3048)
			(end -0.1016 -0.2794)
			(stroke
				(width 0.1)
				(type default)
			)
			(layer "F.Fab")
		)
		(fp_line
			(start -0.6858 -0.3048)
			(end -0.1016 -0.3048)
			(stroke
				(width 0.1)
				(type default)
			)
			(layer "F.Fab")
		)
		(fp_line
			(start 0.1016 -0.2794)
			(end 0.1016 -0.3048)
			(stroke
				(width 0.1)
				(type default)
			)
			(layer "F.Fab")
		)
		(fp_line
			(start -0.1016 -0.2794)
			(end 0.1016 -0.2794)
			(stroke
				(width 0.1)
				(type default)
			)
			(layer "F.Fab")
		)
		(fp_line
			(start 0.1016 0.2794)
			(end -0.1016 0.2794)
			(stroke
				(width 0.1)
				(type default)
			)
			(layer "F.Fab")
		)
		(fp_line
			(start -0.1016 0.2794)
			(end -0.1016 0.3048)
			(stroke
				(width 0.1)
				(type default)
			)
			(layer "F.Fab")
		)
		(fp_line
			(start 0.6858 0.3048)
			(end 0.1016 0.3048)
			(stroke
				(width 0.1)
				(type default)
			)
			(layer "F.Fab")
		)
		(fp_line
			(start 0.1016 0.3048)
			(end 0.1016 0.2794)
			(stroke
				(width 0.1)
				(type default)
			)
			(layer "F.Fab")
		)
		(fp_line
			(start -0.1016 0.3048)
			(end -0.6858 0.3048)
			(stroke
				(width 0.1)
				(type default)
			)
			(layer "F.Fab")
		)
		(fp_line
			(start -0.6858 0.3048)
			(end -0.6858 -0.3048)
			(stroke
				(width 0.1)
				(type default)
			)
			(layer "F.Fab")
		)
		(pad "1" smd rect
			(at -0.40005 0 270)
			(size 0.4572 0.508)
			(layers "F.Cu" "F.Mask" "F.Paste")
			(net "P2E_MB_BMC_RX_BUF2_C_DN<0>")
		)
		(pad "2" smd rect
			(at 0.40005 0 270)
			(size 0.4572 0.508)
			(layers "F.Cu" "F.Mask" "F.Paste")
			(net "P2E_MB_BMC_RX_BUF_DN<0>")
		)
	)
)
